(kicad_pcb
	(version 20241229)
	(generator "pcbnew")
	(generator_version "9.0")
	(general
		(thickness 1.6642)
		(legacy_teardrops no)
	)
	(paper "A3")
	(title_block
		(title "PolarFire SoM")
		(date "2025-07-22")
		(rev "1.1.4")
		(company "Antmicro Ltd")
		(comment 1 "www.antmicro.com")
		(comment 9 "footprints 417-420 of 470")
	)
	(layers
		(0 "F.Cu" mixed)
		(4 "In1.Cu" power)
		(6 "In2.Cu" signal)
		(8 "In3.Cu" power)
		(10 "In4.Cu" signal)
		(12 "In5.Cu" power)
		(14 "In6.Cu" power)
		(16 "In7.Cu" signal)
		(18 "In8.Cu" power)
		(20 "In9.Cu" signal)
		(22 "In10.Cu" power)
		(24 "In11.Cu" signal)
		(26 "In12.Cu" signal)
		(2 "B.Cu" mixed)
		(9 "F.Adhes" user "F.Adhesive")
		(11 "B.Adhes" user "B.Adhesive")
		(13 "F.Paste" user)
		(15 "B.Paste" user)
		(5 "F.SilkS" user "F.Silkscreen")
		(7 "B.SilkS" user "B.Silkscreen")
		(1 "F.Mask" user)
		(3 "B.Mask" user)
		(17 "Dwgs.User" user "User.Drawings")
		(19 "Cmts.User" user "User.Comments")
		(21 "Eco1.User" user "User.Eco1")
		(23 "Eco2.User" user "User.Eco2")
		(25 "Edge.Cuts" user)
		(27 "Margin" user)
		(31 "F.CrtYd" user "F.Courtyard")
		(29 "B.CrtYd" user "B.Courtyard")
		(35 "F.Fab" user)
		(33 "B.Fab" user)
	)
	(footprint "antmicro-footprints:C_0402_1005Metric"
		(layer "B.Cu")
		(at 222.43 153.74)
		(descr "Capacitor SMD 0402")
		(tags "capacitor SMD 0402")
		(property "Reference" "C12"
			(at 0.94 1.7 0)
			(layer "B.SilkS")
			(effects
				(font
					(size 0.7 0.7)
					(thickness 0.15)
				)
				(justify right bottom mirror)
			)
		)
		(property "Value" "C_100n_0402"
			(at -1.022927 -2.155213 0)
			(layer "B.Fab")
			(hide yes)
			(effects
				(font
					(size 0.7 0.7)
					(thickness 0.15)
				)
				(justify right bottom mirror)
			)
		)
		(property "Datasheet" "https://www.murata.com/products/productdetail?partno=GRM155R61H104KE14%23"
			(at 0 0 0)
			(layer "F.Fab")
			(hide yes)
			(effects
				(font
					(size 1.27 1.27)
					(thickness 0.15)
				)
			)
		)
		(property "Description" "SMD Multilayer Ceramic Capacitor, 0.1 µF, 50 V, 0402 [1005 Metric], ± 10%, X5R, GRM Series"
			(at 0 0 0)
			(layer "F.Fab")
			(hide yes)
			(effects
				(font
					(size 1.27 1.27)
					(thickness 0.15)
				)
			)
		)
		(property "Author" "Antmicro"
			(at 0 0 0)
			(layer "B.Fab")
			(hide yes)
			(effects
				(font
					(size 1 1)
					(thickness 0.15)
				)
				(justify mirror)
			)
		)
		(property "Dielectric" "X5R"
			(at 0 0 0)
			(layer "B.Fab")
			(hide yes)
			(effects
				(font
					(size 1 1)
					(thickness 0.15)
				)
				(justify mirror)
			)
		)
		(property "License" "Apache-2.0"
			(at 0 0 0)
			(layer "B.Fab")
			(hide yes)
			(effects
				(font
					(size 1 1)
					(thickness 0.15)
				)
				(justify mirror)
			)
		)
		(property "MPN" "GRM155R61H104KE14D"
			(at 0 0 0)
			(layer "B.Fab")
			(hide yes)
			(effects
				(font
					(size 1 1)
					(thickness 0.15)
				)
				(justify mirror)
			)
		)
		(property "Manufacturer" "Murata"
			(at 0 0 0)
			(layer "B.Fab")
			(hide yes)
			(effects
				(font
					(size 1 1)
					(thickness 0.15)
				)
				(justify mirror)
			)
		)
		(property "Public" ""
			(at 0 0 0)
			(layer "B.Fab")
			(hide yes)
			(effects
				(font
					(size 1 1)
					(thickness 0.15)
				)
				(justify mirror)
			)
		)
		(property "Val" "100n"
			(at 0 0 0)
			(layer "B.Fab")
			(hide yes)
			(effects
				(font
					(size 1 1)
					(thickness 0.15)
				)
				(justify mirror)
			)
		)
		(property "Voltage" "50V"
			(at 0 0 0)
			(layer "B.Fab")
			(hide yes)
			(effects
				(font
					(size 1 1)
					(thickness 0.15)
				)
				(justify mirror)
			)
		)
		(sheetname "/PCIe/")
		(sheetfile "pcie.kicad_sch")
		(attr smd)
		(fp_rect
			(start -0.925 0.47)
			(end 0.925 -0.47)
			(stroke
				(width 0.05)
				(type default)
			)
			(fill no)
			(layer "B.CrtYd")
		)
		(fp_line
			(start -0.494 -0.248)
			(end -0.494 0.25)
			(stroke
				(width 0.15)
				(type solid)
			)
			(layer "B.Fab")
		)
		(fp_line
			(start -0.494 0.25)
			(end 0.504 0.25)
			(stroke
				(width 0.15)
				(type solid)
			)
			(layer "B.Fab")
		)
		(fp_line
			(start 0.504 -0.248)
			(end -0.494 -0.248)
			(stroke
				(width 0.15)
				(type solid)
			)
			(layer "B.Fab")
		)
		(fp_line
			(start 0.504 0.25)
			(end 0.504 -0.248)
			(stroke
				(width 0.15)
				(type solid)
			)
			(layer "B.Fab")
		)
		(fp_text user "License: Apache-2.0"
			(at -0.939 -5.799 180)
			(layer "B.Fab")
			(effects
				(font
					(size 0.7 0.7)
					(thickness 0.15)
				)
				(justify left bottom mirror)
			)
		)
		(fp_text user "${REFERENCE}"
			(at -0.939 -4.599 180)
			(layer "B.Fab")
			(effects
				(font
					(size 0.7 0.7)
					(thickness 0.15)
				)
				(justify left bottom mirror)
			)
		)
		(fp_text user "Author: Antmicro"
			(at -0.939 -3.399 180)
			(layer "B.Fab")
			(effects
				(font
					(size 0.7 0.7)
					(thickness 0.15)
				)
				(justify left bottom mirror)
			)
		)
		(pad "1" smd roundrect
			(at -0.48 0)
			(size 0.59 0.64)
			(layers "B.Cu" "B.Mask" "B.Paste")
			(roundrect_rratio 0.25)
			(net 417 "GND")
			(pintype "passive")
		)
		(pad "2" smd roundrect
			(at 0.48 0)
			(size 0.59 0.64)
			(layers "B.Cu" "B.Mask" "B.Paste")
			(roundrect_rratio 0.25)
			(net 418 "+2V5")
			(pintype "passive")
		)
	)
	(footprint "antmicro-footprints:R_0402_1005Metric"
		(layer "B.Cu")
		(at 178.51 139.27 90)
		(descr "Resistor SMD 0402")
		(tags "resistor SMD 0402")
		(property "Reference" "R93"
			(at -10.755 10.64 90)
			(layer "B.SilkS")
			(effects
				(font
					(size 0.7 0.7)
					(thickness 0.15)
				)
				(justify right bottom mirror)
			)
		)
		(property "Value" "R_0R_0402"
			(at -1.011843 -1.772046 90)
			(layer "B.Fab")
			(hide yes)
			(effects
				(font
					(size 0.7 0.7)
					(thickness 0.15)
				)
				(justify right bottom mirror)
			)
		)
		(property "Datasheet" "https://industrial.panasonic.com/cdbs/www-data/pdf/RDA0000/AOA0000C301.pdf"
			(at 0 0 90)
			(layer "F.Fab")
			(hide yes)
			(effects
				(font
					(size 1.27 1.27)
					(thickness 0.15)
				)
			)
		)
		(property "Description" "SMD Chip Resistor, Jumper, 0 ohm, 100 mW, 0402 [1005 Metric], Thick Film, General Purpose"
			(at 0 0 90)
			(layer "F.Fab")
			(hide yes)
			(effects
				(font
					(size 1.27 1.27)
					(thickness 0.15)
				)
			)
		)
		(property "Author" "Antmicro"
			(at 317.78 -39.24 0)
			(layer "B.Fab")
			(hide yes)
			(effects
				(font
					(size 1 1)
					(thickness 0.15)
				)
				(justify mirror)
			)
		)
		(property "Current" "1A"
			(at 317.78 -39.24 0)
			(layer "B.Fab")
			(hide yes)
			(effects
				(font
					(size 1 1)
					(thickness 0.15)
				)
				(justify mirror)
			)
		)
		(property "DNP" "DNP"
			(at 317.78 -39.24 0)
			(layer "B.Fab")
			(hide yes)
			(effects
				(font
					(size 1 1)
					(thickness 0.15)
				)
				(justify mirror)
			)
		)
		(property "License" "Apache-2.0"
			(at 317.78 -39.24 0)
			(layer "B.Fab")
			(hide yes)
			(effects
				(font
					(size 1 1)
					(thickness 0.15)
				)
				(justify mirror)
			)
		)
		(property "MPN" "ERJ2GE0R00X"
			(at 317.78 -39.24 0)
			(layer "B.Fab")
			(hide yes)
			(effects
				(font
					(size 1 1)
					(thickness 0.15)
				)
				(justify mirror)
			)
		)
		(property "Manufacturer" "Panasonic"
			(at 317.78 -39.24 0)
			(layer "B.Fab")
			(hide yes)
			(effects
				(font
					(size 1 1)
					(thickness 0.15)
				)
				(justify mirror)
			)
		)
		(property "Public" ""
			(at 317.78 -39.24 0)
			(layer "B.Fab")
			(hide yes)
			(effects
				(font
					(size 1 1)
					(thickness 0.15)
				)
				(justify mirror)
			)
		)
		(property "Tolerance" "~"
			(at 317.78 -39.24 0)
			(layer "B.Fab")
			(hide yes)
			(effects
				(font
					(size 1 1)
					(thickness 0.15)
				)
				(justify mirror)
			)
		)
		(property "Val" "0R"
			(at 317.78 -39.24 0)
			(layer "B.Fab")
			(hide yes)
			(effects
				(font
					(size 1 1)
					(thickness 0.15)
				)
				(justify mirror)
			)
		)
		(sheetname "/Supply/")
		(sheetfile "supply.kicad_sch")
		(attr smd)
		(fp_rect
			(start -0.925 0.47)
			(end 0.925 -0.47)
			(stroke
				(width 0.05)
				(type default)
			)
			(fill no)
			(layer "B.CrtYd")
		)
		(fp_rect
			(start -0.5 0.25)
			(end 0.5 -0.25)
			(stroke
				(width 0.15)
				(type solid)
			)
			(fill no)
			(layer "B.Fab")
		)
		(fp_text user "License: Apache-2.0"
			(at -0.95 -5.169 270)
			(layer "B.Fab")
			(effects
				(font
					(size 0.7 0.7)
					(thickness 0.15)
				)
				(justify left bottom mirror)
			)
		)
		(fp_text user "Author: Antmicro"
			(at -0.95 -4.169 270)
			(layer "B.Fab")
			(effects
				(font
					(size 0.7 0.7)
					(thickness 0.15)
				)
				(justify left bottom mirror)
			)
		)
		(fp_text user "${REFERENCE}"
			(at -0.95 -3.168 270)
			(layer "B.Fab")
			(effects
				(font
					(size 0.7 0.7)
					(thickness 0.15)
				)
				(justify left bottom mirror)
			)
		)
		(pad "1" smd roundrect
			(at -0.48 0 90)
			(size 0.59 0.64)
			(layers "B.Cu" "B.Mask" "B.Paste")
			(roundrect_rratio 0.25)
			(net 209 "/Supply/SENSE1_P")
			(pintype "passive")
		)
		(pad "2" smd roundrect
			(at 0.48 0 90)
			(size 0.59 0.64)
			(layers "B.Cu" "B.Mask" "B.Paste")
			(roundrect_rratio 0.25)
			(net 576 "Net-(U6-SENSE1+)")
			(pintype "passive")
		)
	)
	(footprint "antmicro-footprints:C_0402_1005Metric"
		(layer "B.Cu")
		(at 201.704 138.09 180)
		(descr "Capacitor SMD 0402")
		(tags "capacitor SMD 0402")
		(property "Reference" "C8"
			(at -0.956 -1.44 0)
			(layer "B.SilkS")
			(effects
				(font
					(size 0.7 0.7)
					(thickness 0.15)
				)
				(justify left bottom mirror)
			)
		)
		(property "Value" "C_100n_0402"
			(at -1.022927 -2.155213 0)
			(layer "B.Fab")
			(hide yes)
			(effects
				(font
					(size 0.7 0.7)
					(thickness 0.15)
				)
				(justify left bottom mirror)
			)
		)
		(property "Datasheet" "https://www.murata.com/products/productdetail?partno=GRM155R61H104KE14%23"
			(at 0 0 180)
			(layer "F.Fab")
			(hide yes)
			(effects
				(font
					(size 1.27 1.27)
					(thickness 0.15)
				)
			)
		)
		(property "Description" "SMD Multilayer Ceramic Capacitor, 0.1 µF, 50 V, 0402 [1005 Metric], ± 10%, X5R, GRM Series"
			(at 0 0 180)
			(layer "F.Fab")
			(hide yes)
			(effects
				(font
					(size 1.27 1.27)
					(thickness 0.15)
				)
			)
		)
		(property "Author" "Antmicro"
			(at 403.408 276.18 0)
			(layer "B.Fab")
			(hide yes)
			(effects
				(font
					(size 1 1)
					(thickness 0.15)
				)
				(justify mirror)
			)
		)
		(property "Dielectric" "X5R"
			(at 403.408 276.18 0)
			(layer "B.Fab")
			(hide yes)
			(effects
				(font
					(size 1 1)
					(thickness 0.15)
				)
				(justify mirror)
			)
		)
		(property "License" "Apache-2.0"
			(at 403.408 276.18 0)
			(layer "B.Fab")
			(hide yes)
			(effects
				(font
					(size 1 1)
					(thickness 0.15)
				)
				(justify mirror)
			)
		)
		(property "MPN" "GRM155R61H104KE14D"
			(at 403.408 276.18 0)
			(layer "B.Fab")
			(hide yes)
			(effects
				(font
					(size 1 1)
					(thickness 0.15)
				)
				(justify mirror)
			)
		)
		(property "Manufacturer" "Murata"
			(at 403.408 276.18 0)
			(layer "B.Fab")
			(hide yes)
			(effects
				(font
					(size 1 1)
					(thickness 0.15)
				)
				(justify mirror)
			)
		)
		(property "Public" ""
			(at 403.408 276.18 0)
			(layer "B.Fab")
			(hide yes)
			(effects
				(font
					(size 1 1)
					(thickness 0.15)
				)
				(justify mirror)
			)
		)
		(property "Val" "100n"
			(at 403.408 276.18 0)
			(layer "B.Fab")
			(hide yes)
			(effects
				(font
					(size 1 1)
					(thickness 0.15)
				)
				(justify mirror)
			)
		)
		(property "Voltage" "50V"
			(at 403.408 276.18 0)
			(layer "B.Fab")
			(hide yes)
			(effects
				(font
					(size 1 1)
					(thickness 0.15)
				)
				(justify mirror)
			)
		)
		(sheetname "/FPGA Supply/")
		(sheetfile "fpga-supply.kicad_sch")
		(attr smd)
		(fp_rect
			(start -0.925 0.47)
			(end 0.925 -0.47)
			(stroke
				(width 0.05)
				(type default)
			)
			(fill no)
			(layer "B.CrtYd")
		)
		(fp_line
			(start 0.504 0.25)
			(end 0.504 -0.248)
			(stroke
				(width 0.15)
				(type solid)
			)
			(layer "B.Fab")
		)
		(fp_line
			(start 0.504 -0.248)
			(end -0.494 -0.248)
			(stroke
				(width 0.15)
				(type solid)
			)
			(layer "B.Fab")
		)
		(fp_line
			(start -0.494 0.25)
			(end 0.504 0.25)
			(stroke
				(width 0.15)
				(type solid)
			)
			(layer "B.Fab")
		)
		(fp_line
			(start -0.494 -0.248)
			(end -0.494 0.25)
			(stroke
				(width 0.15)
				(type solid)
			)
			(layer "B.Fab")
		)
		(fp_text user "License: Apache-2.0"
			(at -0.939 -5.799 0)
			(layer "B.Fab")
			(effects
				(font
					(size 0.7 0.7)
					(thickness 0.15)
				)
				(justify left bottom mirror)
			)
		)
		(fp_text user "${REFERENCE}"
			(at -0.939 -4.599 0)
			(layer "B.Fab")
			(effects
				(font
					(size 0.7 0.7)
					(thickness 0.15)
				)
				(justify left bottom mirror)
			)
		)
		(fp_text user "Author: Antmicro"
			(at -0.939 -3.399 0)
			(layer "B.Fab")
			(effects
				(font
					(size 0.7 0.7)
					(thickness 0.15)
				)
				(justify left bottom mirror)
			)
		)
		(pad "1" smd roundrect
			(at -0.48 0 180)
			(size 0.59 0.64)
			(layers "B.Cu" "B.Mask" "B.Paste")
			(roundrect_rratio 0.25)
			(net 417 "GND")
			(pintype "passive")
		)
		(pad "2" smd roundrect
			(at 0.48 0 180)
			(size 0.59 0.64)
			(layers "B.Cu" "B.Mask" "B.Paste")
			(roundrect_rratio 0.25)
			(net 1 "/FPGA Supply/XCVR_VREF")
			(pintype "passive")
		)
	)
	(footprint "antmicro-footprints:C_0402_1005Metric"
		(layer "B.Cu")
		(at 193.96 124.26 180)
		(descr "Capacitor SMD 0402")
		(tags "capacitor SMD 0402")
		(property "Reference" "C5"
			(at -0.815 1.56 0)
			(layer "B.SilkS")
			(effects
				(font
					(size 0.7 0.7)
					(thickness 0.15)
				)
				(justify left bottom mirror)
			)
		)
		(property "Value" "C_3n3_0402"
			(at -1.022927 -2.155213 0)
			(layer "B.Fab")
			(hide yes)
			(effects
				(font
					(size 0.7 0.7)
					(thickness 0.15)
				)
				(justify left bottom mirror)
			)
		)
		(property "Datasheet" "https://www.kemet.com/en/us/capacitors/product/C0402C332K5RAC.html"
			(at 0 0 180)
			(layer "F.Fab")
			(hide yes)
			(effects
				(font
					(size 1.27 1.27)
					(thickness 0.15)
				)
			)
		)
		(property "Description" "SMD Multilayer Ceramic Capacitor, 3300 pF, 50 V, 0402 [1005 Metric], ± 10%, X7R, MC"
			(at 0 0 180)
			(layer "F.Fab")
			(hide yes)
			(effects
				(font
					(size 1.27 1.27)
					(thickness 0.15)
				)
			)
		)
		(property "Author" "Antmicro"
			(at 387.92 248.52 0)
			(layer "B.Fab")
			(hide yes)
			(effects
				(font
					(size 1 1)
					(thickness 0.15)
				)
				(justify mirror)
			)
		)
		(property "Dielectric" "X7R"
			(at 387.92 248.52 0)
			(layer "B.Fab")
			(hide yes)
			(effects
				(font
					(size 1 1)
					(thickness 0.15)
				)
				(justify mirror)
			)
		)
		(property "License" "Apache-2.0"
			(at 387.92 248.52 0)
			(layer "B.Fab")
			(hide yes)
			(effects
				(font
					(size 1 1)
					(thickness 0.15)
				)
				(justify mirror)
			)
		)
		(property "MPN" "C0402C332K5RAC"
			(at 387.92 248.52 0)
			(layer "B.Fab")
			(hide yes)
			(effects
				(font
					(size 1 1)
					(thickness 0.15)
				)
				(justify mirror)
			)
		)
		(property "Manufacturer" "KEMET"
			(at 387.92 248.52 0)
			(layer "B.Fab")
			(hide yes)
			(effects
				(font
					(size 1 1)
					(thickness 0.15)
				)
				(justify mirror)
			)
		)
		(property "Public" ""
			(at 387.92 248.52 0)
			(layer "B.Fab")
			(hide yes)
			(effects
				(font
					(size 1 1)
					(thickness 0.15)
				)
				(justify mirror)
			)
		)
		(property "Val" "3n3"
			(at 387.92 248.52 0)
			(layer "B.Fab")
			(hide yes)
			(effects
				(font
					(size 1 1)
					(thickness 0.15)
				)
				(justify mirror)
			)
		)
		(property "Voltage" "50V"
			(at 387.92 248.52 0)
			(layer "B.Fab")
			(hide yes)
			(effects
				(font
					(size 1 1)
					(thickness 0.15)
				)
				(justify mirror)
			)
		)
		(sheetname "/FPGA Supply/")
		(sheetfile "fpga-supply.kicad_sch")
		(attr smd)
		(fp_rect
			(start -0.925 0.47)
			(end 0.925 -0.47)
			(stroke
				(width 0.05)
				(type default)
			)
			(fill no)
			(layer "B.CrtYd")
		)
		(fp_line
			(start 0.504 0.25)
			(end 0.504 -0.248)
			(stroke
				(width 0.15)
				(type solid)
			)
			(layer "B.Fab")
		)
		(fp_line
			(start 0.504 -0.248)
			(end -0.494 -0.248)
			(stroke
				(width 0.15)
				(type solid)
			)
			(layer "B.Fab")
		)
		(fp_line
			(start -0.494 0.25)
			(end 0.504 0.25)
			(stroke
				(width 0.15)
				(type solid)
			)
			(layer "B.Fab")
		)
		(fp_line
			(start -0.494 -0.248)
			(end -0.494 0.25)
			(stroke
				(width 0.15)
				(type solid)
			)
			(layer "B.Fab")
		)
		(fp_text user "License: Apache-2.0"
			(at -0.939 -5.799 0)
			(layer "B.Fab")
			(effects
				(font
					(size 0.7 0.7)
					(thickness 0.15)
				)
				(justify left bottom mirror)
			)
		)
		(fp_text user "Author: Antmicro"
			(at -0.939 -3.399 0)
			(layer "B.Fab")
			(effects
				(font
					(size 0.7 0.7)
					(thickness 0.15)
				)
				(justify left bottom mirror)
			)
		)
		(fp_text user "${REFERENCE}"
			(at -0.939 -4.599 0)
			(layer "B.Fab")
			(effects
				(font
					(size 0.7 0.7)
					(thickness 0.15)
				)
				(justify left bottom mirror)
			)
		)
		(pad "1" smd roundrect
			(at -0.48 0 180)
			(size 0.59 0.64)
			(layers "B.Cu" "B.Mask" "B.Paste")
			(roundrect_rratio 0.25)
			(net 417 "GND")
			(pintype "passive")
		)
		(pad "2" smd roundrect
			(at 0.48 0 180)
			(size 0.59 0.64)
			(layers "B.Cu" "B.Mask" "B.Paste")
			(roundrect_rratio 0.25)
			(net 2 "+1V1")
			(pintype "passive")
		)
	)
)
